# T6G (Grand Teton) — schematic netlist excerpt (pin names and nets, part order shuffled) for the footprints in the layout excerpt that follows; sources: Cadence DE-HDL packaged netlist, KiCad conversion of 04192023_DAF0TMB3IC0_F0TG_MB_C_brd_V02_OCP.brd

PR436  Q_RES  0 5% CHIP  pkg 0402LF  page 210 : A = NC_PVDDCR_CPU0_P1_IMON8 ; B = GND
PC591_1  Q_CAP  22UF 16V 20% X6S  pkg C0805  page 198 : A = SW_P12V_AUX_PVDDCR_SOC_P0_FLT ; B = GND
PC2240  Q_CAP  10UF 16V 10% X6S  pkg C0805  page 152 : A = P12V_SCM_R ; B = GND

(kicad_pcb
	(version 20260206)
	(generator "pcbnew")
	(generator_version "10.0")
	(general
		(thickness 1.6)
		(legacy_teardrops no)
	)
	(paper "A4")
	(title_block
		(title "04192023_DAF0TMB3IC0_F0TG_MB_C_brd_V02_OCP.brd")
		(comment 1 "Grand Teton / footprints 5752-5754 of 8354")
	)
	(layers
		(0 "F.Cu" signal "TOP")
		(4 "In1.Cu" signal "GND")
		(6 "In2.Cu" signal "IN1")
		(8 "In3.Cu" signal "GND1")
		(10 "In4.Cu" signal "IN2")
		(12 "In5.Cu" signal "GND2")
		(14 "In6.Cu" signal "IN3")
		(16 "In7.Cu" signal "GND3")
		(18 "In8.Cu" signal "VCC")
		(20 "In9.Cu" signal "VCC1")
		(22 "In10.Cu" signal "GND4")
		(24 "In11.Cu" signal "IN4")
		(26 "In12.Cu" signal "GND5")
		(28 "In13.Cu" signal "IN5")
		(30 "In14.Cu" signal "GND6")
		(32 "In15.Cu" signal "IN6")
		(34 "In16.Cu" signal "GND7")
		(2 "B.Cu" signal "BOTTOM")
		(9 "F.Adhes" user "F.Adhesive")
		(11 "B.Adhes" user "B.Adhesive")
		(13 "F.Paste" user "Package Geometry/Pastemask Top")
		(15 "B.Paste" user "Package Geometry/Pastemask Bottom")
		(5 "F.SilkS" user "Ref Des/Silkscreen Top")
		(7 "B.SilkS" user "Ref Des/Silkscreen Bottom")
		(1 "F.Mask" user "Board Geometry/Soldermask Top")
		(3 "B.Mask" user "Board Geometry/Soldermask Bottom")
		(17 "Dwgs.User" user "User.Drawings")
		(19 "Cmts.User" user "User.Comments")
		(21 "Eco1.User" user "User.Eco1")
		(23 "Eco2.User" user "User.Eco2")
		(25 "Edge.Cuts" user "Board Geometry/Outline")
		(27 "Margin" user)
		(31 "F.CrtYd" user "Package Geometry/Place Bound Top")
		(29 "B.CrtYd" user "Package Geometry/Place Bound Bottom")
		(35 "F.Fab" user "Ref Des/Assembly Top")
		(33 "B.Fab" user "Ref Des/Assembly Bottom")
	)
	(footprint ""
		(layer "B.Cu")
		(at 174.98568 -24.653748)
		(property "Reference" "PC2240"
			(at 0 0 0)
			(layer "B.SilkS")
			(hide yes)
			(effects
				(font
					(size 1.27 1.27)
				)
				(justify mirror)
			)
		)
		(property "Value" ""
			(at 0 0 0)
			(layer "B.Fab")
			(effects
				(font
					(size 1.27 1.27)
				)
				(justify mirror)
			)
		)
		(duplicate_pad_numbers_are_jumpers no)
		(fp_line
			(start -1.524 -0.762)
			(end -1.524 0.762)
			(stroke
				(width 0.1524)
				(type default)
			)
			(layer "B.SilkS")
		)
		(fp_line
			(start -1.524 0.762)
			(end 1.524 0.762)
			(stroke
				(width 0.1524)
				(type default)
			)
			(layer "B.SilkS")
		)
		(fp_line
			(start 1.524 -0.762)
			(end -1.524 -0.762)
			(stroke
				(width 0.1524)
				(type default)
			)
			(layer "B.SilkS")
		)
		(fp_line
			(start 1.524 0.762)
			(end 1.524 -0.762)
			(stroke
				(width 0.1524)
				(type default)
			)
			(layer "B.SilkS")
		)
		(fp_line
			(start -1.1049 -0.724916)
			(end 1.1049 -0.724916)
			(stroke
				(width 0.1)
				(type default)
			)
			(layer "B.Fab")
		)
		(fp_line
			(start -1.1049 0.724916)
			(end -1.1049 -0.724916)
			(stroke
				(width 0.1)
				(type default)
			)
			(layer "B.Fab")
		)
		(fp_line
			(start 1.1049 -0.724916)
			(end 1.1049 0.724916)
			(stroke
				(width 0.1)
				(type default)
			)
			(layer "B.Fab")
		)
		(fp_line
			(start 1.1049 0.724916)
			(end -1.1049 0.724916)
			(stroke
				(width 0.1)
				(type default)
			)
			(layer "B.Fab")
		)
		(pad "1" smd rect
			(at 0.889 0)
			(size 1.016 1.27)
			(layers "B.Cu" "B.Mask" "B.Paste")
			(net "P12V_SCM_R")
		)
		(pad "2" smd rect
			(at -0.889 0)
			(size 1.016 1.27)
			(layers "B.Cu" "B.Mask" "B.Paste")
			(net "GND")
		)
	)
	(footprint ""
		(layer "B.Cu")
		(at 97.902522 -150.698962 -90)
		(property "Reference" "PR436"
			(at 0 0 90)
			(layer "B.SilkS")
			(hide yes)
			(effects
				(font
					(size 1.27 1.27)
				)
				(justify mirror)
			)
		)
		(property "Value" ""
			(at 0 0 90)
			(layer "B.Fab")
			(effects
				(font
					(size 1.27 1.27)
				)
				(justify mirror)
			)
		)
		(duplicate_pad_numbers_are_jumpers no)
		(fp_line
			(start -0.7874 0.4064)
			(end 0.7874 0.4064)
			(stroke
				(width 0.1524)
				(type default)
			)
			(layer "B.SilkS")
		)
		(fp_line
			(start 0.7874 0.4064)
			(end 0.7874 -0.4064)
			(stroke
				(width 0.1524)
				(type default)
			)
			(layer "B.SilkS")
		)
		(fp_line
			(start -0.7874 -0.4064)
			(end -0.7874 0.4064)
			(stroke
				(width 0.1524)
				(type default)
			)
			(layer "B.SilkS")
		)
		(fp_line
			(start 0.7874 -0.4064)
			(end -0.7874 -0.4064)
			(stroke
				(width 0.1524)
				(type default)
			)
			(layer "B.SilkS")
		)
		(fp_line
			(start -0.67945 0.3048)
			(end -0.120396 0.3048)
			(stroke
				(width 0.1)
				(type default)
			)
			(layer "B.Fab")
		)
		(fp_line
			(start -0.120396 0.3048)
			(end -0.120396 0.2794)
			(stroke
				(width 0.1)
				(type default)
			)
			(layer "B.Fab")
		)
		(fp_line
			(start 0.12065 0.3048)
			(end 0.67945 0.3048)
			(stroke
				(width 0.1)
				(type default)
			)
			(layer "B.Fab")
		)
		(fp_line
			(start 0.67945 0.3048)
			(end 0.67945 -0.305054)
			(stroke
				(width 0.1)
				(type default)
			)
			(layer "B.Fab")
		)
		(fp_line
			(start -0.120396 0.2794)
			(end 0.12065 0.2794)
			(stroke
				(width 0.1)
				(type default)
			)
			(layer "B.Fab")
		)
		(fp_line
			(start 0.12065 0.2794)
			(end 0.12065 0.3048)
			(stroke
				(width 0.1)
				(type default)
			)
			(layer "B.Fab")
		)
		(fp_line
			(start -0.12065 -0.2794)
			(end -0.12065 -0.3048)
			(stroke
				(width 0.1)
				(type default)
			)
			(layer "B.Fab")
		)
		(fp_line
			(start 0.12065 -0.2794)
			(end -0.12065 -0.2794)
			(stroke
				(width 0.1)
				(type default)
			)
			(layer "B.Fab")
		)
		(fp_line
			(start -0.67945 -0.3048)
			(end -0.67945 0.3048)
			(stroke
				(width 0.1)
				(type default)
			)
			(layer "B.Fab")
		)
		(fp_line
			(start -0.12065 -0.3048)
			(end -0.67945 -0.3048)
			(stroke
				(width 0.1)
				(type default)
			)
			(layer "B.Fab")
		)
		(fp_line
			(start 0.12065 -0.305054)
			(end 0.12065 -0.2794)
			(stroke
				(width 0.1)
				(type default)
			)
			(layer "B.Fab")
		)
		(fp_line
			(start 0.67945 -0.305054)
			(end 0.12065 -0.305054)
			(stroke
				(width 0.1)
				(type default)
			)
			(layer "B.Fab")
		)
		(pad "1" smd circle
			(at 0.40005 0 90)
			(size 0 0)
			(layers "B.Cu" "B.Mask" "B.Paste")
			(net "NC_PVDDCR_CPU0_P1_IMON8")
		)
		(pad "2" smd circle
			(at -0.40005 0 90)
			(size 0 0)
			(layers "B.Cu" "B.Mask" "B.Paste")
			(net "GND")
		)
	)
	(footprint ""
		(layer "B.Cu")
		(at 394.765276 -177.294794 -90)
		(property "Reference" "PC591_1"
			(at 0 0 90)
			(layer "B.SilkS")
			(hide yes)
			(effects
				(font
					(size 1.27 1.27)
				)
				(justify mirror)
			)
		)
		(property "Value" ""
			(at 0 0 90)
			(layer "B.Fab")
			(effects
				(font
					(size 1.27 1.27)
				)
				(justify mirror)
			)
		)
		(duplicate_pad_numbers_are_jumpers no)
		(fp_line
			(start -1.524 0.762)
			(end 1.524 0.762)
			(stroke
				(width 0.1524)
				(type default)
			)
			(layer "B.SilkS")
		)
		(fp_line
			(start 1.524 0.762)
			(end 1.524 -0.762)
			(stroke
				(width 0.1524)
				(type default)
			)
			(layer "B.SilkS")
		)
		(fp_line
			(start -1.524 -0.762)
			(end -1.524 0.762)
			(stroke
				(width 0.1524)
				(type default)
			)
			(layer "B.SilkS")
		)
		(fp_line
			(start 1.524 -0.762)
			(end -1.524 -0.762)
			(stroke
				(width 0.1524)
				(type default)
			)
			(layer "B.SilkS")
		)
		(fp_line
			(start -1.1049 0.724916)
			(end -1.1049 -0.724916)
			(stroke
				(width 0.1)
				(type default)
			)
			(layer "B.Fab")
		)
		(fp_line
			(start 1.1049 0.724916)
			(end -1.1049 0.724916)
			(stroke
				(width 0.1)
				(type default)
			)
			(layer "B.Fab")
		)
		(fp_line
			(start -1.1049 -0.724916)
			(end 1.1049 -0.724916)
			(stroke
				(width 0.1)
				(type default)
			)
			(layer "B.Fab")
		)
		(fp_line
			(start 1.1049 -0.724916)
			(end 1.1049 0.724916)
			(stroke
				(width 0.1)
				(type default)
			)
			(layer "B.Fab")
		)
		(pad "1" smd rect
			(at 0.889 0 270)
			(size 1.016 1.27)
			(layers "B.Cu" "B.Mask" "B.Paste")
			(net "SW_P12V_AUX_PVDDCR_SOC_P0_FLT")
		)
		(pad "2" smd rect
			(at -0.889 0 270)
			(size 1.016 1.27)
			(layers "B.Cu" "B.Mask" "B.Paste")
			(net "GND")
		)
	)
)
